# T6G (Grand Teton) — schematic netlist excerpt (pin names and nets, part order shuffled) for the footprints in the layout excerpt that follows; sources: Cadence DE-HDL packaged netlist, KiCad conversion of 04192023_DAF0TMB3IC0_F0TG_MB_C_brd_V02_OCP.brd

C2540  Q_CAP  22UF 4V 20% X6S  pkg C0402  page 70 : A = PVDDCR_SOC_P0 ; B = GND
R445  Q_RES  4.7K 5% CHIP  pkg 0402LF  page 28 : A = IRQ_BMC_SMI_N ; B = PVDD18_S5_P0

(kicad_pcb
	(version 20260206)
	(generator "pcbnew")
	(generator_version "10.0")
	(general
		(thickness 1.6)
		(legacy_teardrops no)
	)
	(paper "A4")
	(title_block
		(title "04192023_DAF0TMB3IC0_F0TG_MB_C_brd_V02_OCP.brd")
		(comment 1 "Grand Teton / footprints 8341-8342 of 8354")
	)
	(layers
		(0 "F.Cu" signal "TOP")
		(4 "In1.Cu" signal "GND")
		(6 "In2.Cu" signal "IN1")
		(8 "In3.Cu" signal "GND1")
		(10 "In4.Cu" signal "IN2")
		(12 "In5.Cu" signal "GND2")
		(14 "In6.Cu" signal "IN3")
		(16 "In7.Cu" signal "GND3")
		(18 "In8.Cu" signal "VCC")
		(20 "In9.Cu" signal "VCC1")
		(22 "In10.Cu" signal "GND4")
		(24 "In11.Cu" signal "IN4")
		(26 "In12.Cu" signal "GND5")
		(28 "In13.Cu" signal "IN5")
		(30 "In14.Cu" signal "GND6")
		(32 "In15.Cu" signal "IN6")
		(34 "In16.Cu" signal "GND7")
		(2 "B.Cu" signal "BOTTOM")
		(9 "F.Adhes" user "F.Adhesive")
		(11 "B.Adhes" user "B.Adhesive")
		(13 "F.Paste" user "Package Geometry/Pastemask Top")
		(15 "B.Paste" user "Package Geometry/Pastemask Bottom")
		(5 "F.SilkS" user "Ref Des/Silkscreen Top")
		(7 "B.SilkS" user "Ref Des/Silkscreen Bottom")
		(1 "F.Mask" user "Board Geometry/Soldermask Top")
		(3 "B.Mask" user "Board Geometry/Soldermask Bottom")
		(17 "Dwgs.User" user "User.Drawings")
		(19 "Cmts.User" user "User.Comments")
		(21 "Eco1.User" user "User.Eco1")
		(23 "Eco2.User" user "User.Eco2")
		(25 "Edge.Cuts" user "Board Geometry/Outline")
		(27 "Margin" user)
		(31 "F.CrtYd" user "Package Geometry/Place Bound Top")
		(29 "B.CrtYd" user "Package Geometry/Place Bound Bottom")
		(35 "F.Fab" user "Ref Des/Assembly Top")
		(33 "B.Fab" user "Ref Des/Assembly Bottom")
	)
	(footprint ""
		(layer "B.Cu")
		(at 406.698958 -328.926952 180)
		(property "Reference" "R445"
			(at 0 0 0)
			(layer "B.SilkS")
			(hide yes)
			(effects
				(font
					(size 1.27 1.27)
				)
				(justify mirror)
			)
		)
		(property "Value" ""
			(at 0 0 0)
			(layer "B.Fab")
			(effects
				(font
					(size 1.27 1.27)
				)
				(justify mirror)
			)
		)
		(duplicate_pad_numbers_are_jumpers no)
		(fp_line
			(start 0.7874 0.4064)
			(end 0.7874 -0.4064)
			(stroke
				(width 0.1524)
				(type default)
			)
			(layer "B.SilkS")
		)
		(fp_line
			(start 0.7874 -0.4064)
			(end -0.7874 -0.4064)
			(stroke
				(width 0.1524)
				(type default)
			)
			(layer "B.SilkS")
		)
		(fp_line
			(start -0.7874 0.4064)
			(end 0.7874 0.4064)
			(stroke
				(width 0.1524)
				(type default)
			)
			(layer "B.SilkS")
		)
		(fp_line
			(start -0.7874 -0.4064)
			(end -0.7874 0.4064)
			(stroke
				(width 0.1524)
				(type default)
			)
			(layer "B.SilkS")
		)
		(fp_line
			(start 0.67945 0.3048)
			(end 0.67945 -0.305054)
			(stroke
				(width 0.1)
				(type default)
			)
			(layer "B.Fab")
		)
		(fp_line
			(start 0.67945 -0.305054)
			(end 0.12065 -0.305054)
			(stroke
				(width 0.1)
				(type default)
			)
			(layer "B.Fab")
		)
		(fp_line
			(start 0.12065 0.3048)
			(end 0.67945 0.3048)
			(stroke
				(width 0.1)
				(type default)
			)
			(layer "B.Fab")
		)
		(fp_line
			(start 0.12065 0.2794)
			(end 0.12065 0.3048)
			(stroke
				(width 0.1)
				(type default)
			)
			(layer "B.Fab")
		)
		(fp_line
			(start 0.12065 -0.2794)
			(end -0.12065 -0.2794)
			(stroke
				(width 0.1)
				(type default)
			)
			(layer "B.Fab")
		)
		(fp_line
			(start 0.12065 -0.305054)
			(end 0.12065 -0.2794)
			(stroke
				(width 0.1)
				(type default)
			)
			(layer "B.Fab")
		)
		(fp_line
			(start -0.120396 0.3048)
			(end -0.120396 0.2794)
			(stroke
				(width 0.1)
				(type default)
			)
			(layer "B.Fab")
		)
		(fp_line
			(start -0.120396 0.2794)
			(end 0.12065 0.2794)
			(stroke
				(width 0.1)
				(type default)
			)
			(layer "B.Fab")
		)
		(fp_line
			(start -0.12065 -0.2794)
			(end -0.12065 -0.3048)
			(stroke
				(width 0.1)
				(type default)
			)
			(layer "B.Fab")
		)
		(fp_line
			(start -0.12065 -0.3048)
			(end -0.67945 -0.3048)
			(stroke
				(width 0.1)
				(type default)
			)
			(layer "B.Fab")
		)
		(fp_line
			(start -0.67945 0.3048)
			(end -0.120396 0.3048)
			(stroke
				(width 0.1)
				(type default)
			)
			(layer "B.Fab")
		)
		(fp_line
			(start -0.67945 -0.3048)
			(end -0.67945 0.3048)
			(stroke
				(width 0.1)
				(type default)
			)
			(layer "B.Fab")
		)
		(pad "1" smd circle
			(at 0.40005 0)
			(size 0 0)
			(layers "B.Cu" "B.Mask" "B.Paste")
			(net "IRQ_BMC_SMI_N")
		)
		(pad "2" smd circle
			(at -0.40005 0)
			(size 0 0)
			(layers "B.Cu" "B.Mask" "B.Paste")
			(net "PVDD18_S5_P0")
		)
	)
	(footprint ""
		(layer "B.Cu")
		(at 357.835454 -253.43231)
		(property "Reference" "C2540"
			(at 0 0 0)
			(layer "B.SilkS")
			(hide yes)
			(effects
				(font
					(size 1.27 1.27)
				)
				(justify mirror)
			)
		)
		(property "Value" ""
			(at 0 0 0)
			(layer "B.Fab")
			(effects
				(font
					(size 1.27 1.27)
				)
				(justify mirror)
			)
		)
		(duplicate_pad_numbers_are_jumpers no)
		(fp_line
			(start -0.7874 -0.4064)
			(end -0.7874 0.4064)
			(stroke
				(width 0.1524)
				(type default)
			)
			(layer "B.SilkS")
		)
		(fp_line
			(start -0.7874 0.4064)
			(end 0.7874 0.4064)
			(stroke
				(width 0.1524)
				(type default)
			)
			(layer "B.SilkS")
		)
		(fp_line
			(start 0.7874 -0.4064)
			(end -0.7874 -0.4064)
			(stroke
				(width 0.1524)
				(type default)
			)
			(layer "B.SilkS")
		)
		(fp_line
			(start 0.7874 0.4064)
			(end 0.7874 -0.4064)
			(stroke
				(width 0.1524)
				(type default)
			)
			(layer "B.SilkS")
		)
		(fp_line
			(start -0.67945 -0.3048)
			(end -0.67945 0.3048)
			(stroke
				(width 0.1)
				(type default)
			)
			(layer "B.Fab")
		)
		(fp_line
			(start -0.67945 0.3048)
			(end -0.120396 0.3048)
			(stroke
				(width 0.1)
				(type default)
			)
			(layer "B.Fab")
		)
		(fp_line
			(start -0.12065 -0.3048)
			(end -0.67945 -0.3048)
			(stroke
				(width 0.1)
				(type default)
			)
			(layer "B.Fab")
		)
		(fp_line
			(start -0.12065 -0.2794)
			(end -0.12065 -0.3048)
			(stroke
				(width 0.1)
				(type default)
			)
			(layer "B.Fab")
		)
		(fp_line
			(start -0.120396 0.2794)
			(end 0.12065 0.2794)
			(stroke
				(width 0.1)
				(type default)
			)
			(layer "B.Fab")
		)
		(fp_line
			(start -0.120396 0.3048)
			(end -0.120396 0.2794)
			(stroke
				(width 0.1)
				(type default)
			)
			(layer "B.Fab")
		)
		(fp_line
			(start 0.12065 -0.305054)
			(end 0.12065 -0.2794)
			(stroke
				(width 0.1)
				(type default)
			)
			(layer "B.Fab")
		)
		(fp_line
			(start 0.12065 -0.2794)
			(end -0.12065 -0.2794)
			(stroke
				(width 0.1)
				(type default)
			)
			(layer "B.Fab")
		)
		(fp_line
			(start 0.12065 0.2794)
			(end 0.12065 0.3048)
			(stroke
				(width 0.1)
				(type default)
			)
			(layer "B.Fab")
		)
		(fp_line
			(start 0.12065 0.3048)
			(end 0.67945 0.3048)
			(stroke
				(width 0.1)
				(type default)
			)
			(layer "B.Fab")
		)
		(fp_line
			(start 0.67945 -0.305054)
			(end 0.12065 -0.305054)
			(stroke
				(width 0.1)
				(type default)
			)
			(layer "B.Fab")
		)
		(fp_line
			(start 0.67945 0.3048)
			(end 0.67945 -0.305054)
			(stroke
				(width 0.1)
				(type default)
			)
			(layer "B.Fab")
		)
		(pad "1" smd circle
			(at 0.40005 0 180)
			(size 0 0)
			(layers "B.Cu" "B.Mask" "B.Paste")
			(net "PVDDCR_SOC_P0")
		)
		(pad "2" smd circle
			(at -0.40005 0 180)
			(size 0 0)
			(layers "B.Cu" "B.Mask" "B.Paste")
			(net "GND")
		)
	)
)
